(kicad_pcb
	(version 20260206)
	(generator "pcbnew")
	(generator_version "10.0")
	(general
		(thickness 1.6)
		(legacy_teardrops no)
	)
	(paper "A4")
	(title_block
		(title "03242023_DA0F0TMBIJ0_F0T_Motherboard_J_brd_V01_OCP.brd")
		(comment 1 "Grand Teton / footprints 798-803 of 6105")
	)
	(layers
		(0 "F.Cu" signal "TOP")
		(4 "In1.Cu" signal "GND")
		(6 "In2.Cu" signal "IN1")
		(8 "In3.Cu" signal "GND1")
		(10 "In4.Cu" signal "IN2")
		(12 "In5.Cu" signal "GND2")
		(14 "In6.Cu" signal "IN3")
		(16 "In7.Cu" signal "GND3")
		(18 "In8.Cu" signal "VCC")
		(20 "In9.Cu" signal "VCC1")
		(22 "In10.Cu" signal "GND4")
		(24 "In11.Cu" signal "IN4")
		(26 "In12.Cu" signal "GND5")
		(28 "In13.Cu" signal "IN5")
		(30 "In14.Cu" signal "GND6")
		(32 "In15.Cu" signal "IN6")
		(34 "In16.Cu" signal "GND7")
		(2 "B.Cu" signal "BOTTOM")
		(9 "F.Adhes" user "F.Adhesive")
		(11 "B.Adhes" user "B.Adhesive")
		(13 "F.Paste" user "Package Geometry/Pastemask Top")
		(15 "B.Paste" user "Package Geometry/Pastemask Bottom")
		(5 "F.SilkS" user "Ref Des/Silkscreen Top")
		(7 "B.SilkS" user "Ref Des/Silkscreen Bottom")
		(1 "F.Mask" user "Board Geometry/Soldermask Top")
		(3 "B.Mask" user "Board Geometry/Soldermask Bottom")
		(17 "Dwgs.User" user "User.Drawings")
		(19 "Cmts.User" user "User.Comments")
		(21 "Eco1.User" user "User.Eco1")
		(23 "Eco2.User" user "User.Eco2")
		(25 "Edge.Cuts" user "Board Geometry/Outline")
		(27 "Margin" user)
		(31 "F.CrtYd" user "Package Geometry/Place Bound Top")
		(29 "B.CrtYd" user "Package Geometry/Place Bound Bottom")
		(35 "F.Fab" user "Ref Des/Assembly Top")
		(33 "B.Fab" user "Ref Des/Assembly Bottom")
	)
	(footprint ""
		(layer "F.Cu")
		(at 278.474678 -420.6113 90)
		(property "Reference" "U369"
			(at -1.6002 3.870452 90)
			(unlocked yes)
			(layer "F.SilkS")
			(effects
				(font
					(size 0.7874 0.5842)
					(thickness 0.1524)
				)
				(justify left)
			)
		)
		(property "Value" ""
			(at 0 0 90)
			(layer "F.Fab")
			(effects
				(font
					(size 1.27 1.27)
				)
			)
		)
		(duplicate_pad_numbers_are_jumpers no)
		(fp_line
			(start 2.03581 -1.525016)
			(end 0.82423 -1.525016)
			(stroke
				(width 0.1524)
				(type default)
			)
			(layer "F.SilkS")
		)
		(fp_line
			(start 0.82423 -1.525016)
			(end 0 -0.649986)
			(stroke
				(width 0.1524)
				(type default)
			)
			(layer "F.SilkS")
		)
		(fp_line
			(start -0.82423 -1.525016)
			(end -2.03581 -1.525016)
			(stroke
				(width 0.1524)
				(type default)
			)
			(layer "F.SilkS")
		)
		(fp_line
			(start -2.03581 -1.525016)
			(end -2.03581 1.525016)
			(stroke
				(width 0.1524)
				(type default)
			)
			(layer "F.SilkS")
		)
		(fp_line
			(start 0 -0.649986)
			(end -0.82423 -1.525016)
			(stroke
				(width 0.1524)
				(type default)
			)
			(layer "F.SilkS")
		)
		(fp_line
			(start 2.03581 1.525016)
			(end 2.03581 -1.525016)
			(stroke
				(width 0.1524)
				(type default)
			)
			(layer "F.SilkS")
		)
		(fp_line
			(start -2.03581 1.525016)
			(end 2.03581 1.525016)
			(stroke
				(width 0.1524)
				(type default)
			)
			(layer "F.SilkS")
		)
		(fp_poly
			(pts
				(xy -1.501902 -1.539748) (xy -1.886458 -2.309368) (xy -1.117092 -2.309368)
			)
			(stroke
				(width 0)
				(type default)
			)
			(fill yes)
			(layer "F.SilkS")
		)
		(fp_line
			(start 0.87503 -1.525016)
			(end -0.87503 -1.525016)
			(stroke
				(width 0.1)
				(type default)
			)
			(layer "F.Fab")
		)
		(fp_line
			(start -0.87503 -1.525016)
			(end -0.87503 1.525016)
			(stroke
				(width 0.1)
				(type default)
			)
			(layer "F.Fab")
		)
		(fp_line
			(start 0.87503 1.525016)
			(end 0.87503 -1.525016)
			(stroke
				(width 0.1)
				(type default)
			)
			(layer "F.Fab")
		)
		(fp_line
			(start -0.87503 1.525016)
			(end 0.87503 1.525016)
			(stroke
				(width 0.1)
				(type default)
			)
			(layer "F.Fab")
		)
		(fp_poly
			(pts
				(xy -2.12979 -0.943356) (xy -2.89941 -0.5588) (xy -2.89941 -1.328166)
			)
			(stroke
				(width 0)
				(type default)
			)
			(fill yes)
			(layer "F.Fab")
		)
		(pad "1" smd rect
			(at -1.35001 -0.94996)
			(size 0.6096 1.1176)
			(layers "F.Cu" "F.Mask" "F.Paste")
			(net "A_HSC_LOW_GATE")
		)
		(pad "2" smd rect
			(at -1.35001 0)
			(size 0.6096 1.1176)
			(layers "F.Cu" "F.Mask" "F.Paste")
			(net "GND")
		)
		(pad "3" smd rect
			(at -1.35001 0.94996)
			(size 0.6096 1.1176)
			(layers "F.Cu" "F.Mask" "F.Paste")
			(net "A_HSC_LOW")
		)
		(pad "4" smd rect
			(at 1.35001 0.94996)
			(size 0.6096 1.1176)
			(layers "F.Cu" "F.Mask" "F.Paste")
			(net "A_HSC_HIGH")
		)
		(pad "5" smd rect
			(at 1.35001 0)
			(size 0.6096 1.1176)
			(layers "F.Cu" "F.Mask" "F.Paste")
			(net "U369_VDD")
		)
		(pad "6" smd rect
			(at 1.35001 -0.94996)
			(size 0.6096 1.1176)
			(layers "F.Cu" "F.Mask" "F.Paste")
			(net "HSC_D_OC")
		)
	)
	(footprint ""
		(layer "F.Cu")
		(at 117.526816 -249.320558 -90)
		(property "Reference" "C278"
			(at 0 0 270)
			(layer "F.SilkS")
			(hide yes)
			(effects
				(font
					(size 1.27 1.27)
				)
			)
		)
		(property "Value" ""
			(at 0 0 270)
			(layer "F.Fab")
			(effects
				(font
					(size 1.27 1.27)
				)
			)
		)
		(duplicate_pad_numbers_are_jumpers no)
		(fp_line
			(start -0.7874 0.4064)
			(end -0.7874 -0.4064)
			(stroke
				(width 0.1524)
				(type default)
			)
			(layer "F.SilkS")
		)
		(fp_line
			(start 0.7874 0.4064)
			(end -0.7874 0.4064)
			(stroke
				(width 0.1524)
				(type default)
			)
			(layer "F.SilkS")
		)
		(fp_line
			(start -0.7874 -0.4064)
			(end 0.7874 -0.4064)
			(stroke
				(width 0.1524)
				(type default)
			)
			(layer "F.SilkS")
		)
		(fp_line
			(start 0.7874 -0.4064)
			(end 0.7874 0.4064)
			(stroke
				(width 0.1524)
				(type default)
			)
			(layer "F.SilkS")
		)
		(fp_line
			(start -0.67945 0.3048)
			(end -0.67945 -0.305054)
			(stroke
				(width 0.1)
				(type default)
			)
			(layer "F.Fab")
		)
		(fp_line
			(start -0.12065 0.3048)
			(end -0.67945 0.3048)
			(stroke
				(width 0.1)
				(type default)
			)
			(layer "F.Fab")
		)
		(fp_line
			(start 0.120396 0.3048)
			(end 0.120396 0.2794)
			(stroke
				(width 0.1)
				(type default)
			)
			(layer "F.Fab")
		)
		(fp_line
			(start 0.67945 0.3048)
			(end 0.120396 0.3048)
			(stroke
				(width 0.1)
				(type default)
			)
			(layer "F.Fab")
		)
		(fp_line
			(start -0.12065 0.2794)
			(end -0.12065 0.3048)
			(stroke
				(width 0.1)
				(type default)
			)
			(layer "F.Fab")
		)
		(fp_line
			(start 0.120396 0.2794)
			(end -0.12065 0.2794)
			(stroke
				(width 0.1)
				(type default)
			)
			(layer "F.Fab")
		)
		(fp_line
			(start -0.12065 -0.2794)
			(end 0.12065 -0.2794)
			(stroke
				(width 0.1)
				(type default)
			)
			(layer "F.Fab")
		)
		(fp_line
			(start 0.12065 -0.2794)
			(end 0.12065 -0.3048)
			(stroke
				(width 0.1)
				(type default)
			)
			(layer "F.Fab")
		)
		(fp_line
			(start 0.12065 -0.3048)
			(end 0.67945 -0.3048)
			(stroke
				(width 0.1)
				(type default)
			)
			(layer "F.Fab")
		)
		(fp_line
			(start 0.67945 -0.3048)
			(end 0.67945 0.3048)
			(stroke
				(width 0.1)
				(type default)
			)
			(layer "F.Fab")
		)
		(fp_line
			(start -0.67945 -0.305054)
			(end -0.12065 -0.305054)
			(stroke
				(width 0.1)
				(type default)
			)
			(layer "F.Fab")
		)
		(fp_line
			(start -0.12065 -0.305054)
			(end -0.12065 -0.2794)
			(stroke
				(width 0.1)
				(type default)
			)
			(layer "F.Fab")
		)
		(pad "1" smd circle
			(at -0.40005 0 270)
			(size 0 0)
			(layers "F.Cu" "F.Mask" "F.Paste")
			(net "PVCCIN_CPU1")
		)
		(pad "2" smd circle
			(at 0.40005 0 270)
			(size 0 0)
			(layers "F.Cu" "F.Mask" "F.Paste")
			(net "GND")
		)
	)
	(footprint ""
		(layer "F.Cu")
		(at 35.980878 -17.623536 90)
		(property "Reference" "C821"
			(at 0 0 90)
			(layer "F.SilkS")
			(hide yes)
			(effects
				(font
					(size 1.27 1.27)
				)
			)
		)
		(property "Value" ""
			(at 0 0 90)
			(layer "F.Fab")
			(effects
				(font
					(size 1.27 1.27)
				)
			)
		)
		(duplicate_pad_numbers_are_jumpers no)
		(fp_line
			(start 0.299974 -0.150114)
			(end 0.299974 0.150114)
			(stroke
				(width 0.1)
				(type default)
			)
			(layer "F.Fab")
		)
		(fp_line
			(start -0.299974 -0.150114)
			(end 0.299974 -0.150114)
			(stroke
				(width 0.1)
				(type default)
			)
			(layer "F.Fab")
		)
		(fp_line
			(start 0.299974 0.150114)
			(end -0.299974 0.150114)
			(stroke
				(width 0.1)
				(type default)
			)
			(layer "F.Fab")
		)
		(fp_line
			(start -0.299974 0.150114)
			(end -0.299974 -0.150114)
			(stroke
				(width 0.1)
				(type default)
			)
			(layer "F.Fab")
		)
		(pad "1" smd rect
			(at -0.2667 0 90)
			(size 0.3048 0.381)
			(layers "F.Cu" "F.Mask" "F.Paste")
			(net "P5E_CPU1_PE1_TX_C_DP<8>")
		)
		(pad "2" smd rect
			(at 0.2667 0 90)
			(size 0.3048 0.381)
			(layers "F.Cu" "F.Mask" "F.Paste")
			(net "P5E_CPU1_PE1_TX_DP<8>")
		)
	)
	(footprint ""
		(layer "F.Cu")
		(at 82.306668 -17.745202)
		(property "Reference" "R3831"
			(at 0 0 0)
			(layer "F.SilkS")
			(hide yes)
			(effects
				(font
					(size 1.27 1.27)
				)
			)
		)
		(property "Value" ""
			(at 0 0 0)
			(layer "F.Fab")
			(effects
				(font
					(size 1.27 1.27)
				)
			)
		)
		(duplicate_pad_numbers_are_jumpers no)
		(fp_line
			(start -0.7874 -0.4064)
			(end 0.7874 -0.4064)
			(stroke
				(width 0.1524)
				(type default)
			)
			(layer "F.SilkS")
		)
		(fp_line
			(start -0.7874 0.4064)
			(end -0.7874 -0.4064)
			(stroke
				(width 0.1524)
				(type default)
			)
			(layer "F.SilkS")
		)
		(fp_line
			(start 0.7874 -0.4064)
			(end 0.7874 0.4064)
			(stroke
				(width 0.1524)
				(type default)
			)
			(layer "F.SilkS")
		)
		(fp_line
			(start 0.7874 0.4064)
			(end -0.7874 0.4064)
			(stroke
				(width 0.1524)
				(type default)
			)
			(layer "F.SilkS")
		)
		(fp_line
			(start -0.67945 -0.305054)
			(end -0.12065 -0.305054)
			(stroke
				(width 0.1)
				(type default)
			)
			(layer "F.Fab")
		)
		(fp_line
			(start -0.67945 0.3048)
			(end -0.67945 -0.305054)
			(stroke
				(width 0.1)
				(type default)
			)
			(layer "F.Fab")
		)
		(fp_line
			(start -0.12065 -0.305054)
			(end -0.12065 -0.2794)
			(stroke
				(width 0.1)
				(type default)
			)
			(layer "F.Fab")
		)
		(fp_line
			(start -0.12065 -0.2794)
			(end 0.12065 -0.2794)
			(stroke
				(width 0.1)
				(type default)
			)
			(layer "F.Fab")
		)
		(fp_line
			(start -0.12065 0.2794)
			(end -0.12065 0.3048)
			(stroke
				(width 0.1)
				(type default)
			)
			(layer "F.Fab")
		)
		(fp_line
			(start -0.12065 0.3048)
			(end -0.67945 0.3048)
			(stroke
				(width 0.1)
				(type default)
			)
			(layer "F.Fab")
		)
		(fp_line
			(start 0.120396 0.2794)
			(end -0.12065 0.2794)
			(stroke
				(width 0.1)
				(type default)
			)
			(layer "F.Fab")
		)
		(fp_line
			(start 0.120396 0.3048)
			(end 0.120396 0.2794)
			(stroke
				(width 0.1)
				(type default)
			)
			(layer "F.Fab")
		)
		(fp_line
			(start 0.12065 -0.3048)
			(end 0.67945 -0.3048)
			(stroke
				(width 0.1)
				(type default)
			)
			(layer "F.Fab")
		)
		(fp_line
			(start 0.12065 -0.2794)
			(end 0.12065 -0.3048)
			(stroke
				(width 0.1)
				(type default)
			)
			(layer "F.Fab")
		)
		(fp_line
			(start 0.67945 -0.3048)
			(end 0.67945 0.3048)
			(stroke
				(width 0.1)
				(type default)
			)
			(layer "F.Fab")
		)
		(fp_line
			(start 0.67945 0.3048)
			(end 0.120396 0.3048)
			(stroke
				(width 0.1)
				(type default)
			)
			(layer "F.Fab")
		)
		(pad "1" smd circle
			(at -0.40005 0)
			(size 0 0)
			(layers "F.Cu" "F.Mask" "F.Paste")
			(net "P12V_OCP_PWRGD_2")
		)
		(pad "2" smd circle
			(at 0.40005 0)
			(size 0 0)
			(layers "F.Cu" "F.Mask" "F.Paste")
			(net "HP_LVC3_OCP_V3_2_P12V_PWRGD")
		)
	)
	(footprint ""
		(layer "F.Cu")
		(at 70.41896 -61.158628 90)
		(property "Reference" "PC1322"
			(at 0 0 90)
			(layer "F.SilkS")
			(hide yes)
			(effects
				(font
					(size 1.27 1.27)
				)
			)
		)
		(property "Value" ""
			(at 0 0 90)
			(layer "F.Fab")
			(effects
				(font
					(size 1.27 1.27)
				)
			)
		)
		(duplicate_pad_numbers_are_jumpers no)
		(fp_line
			(start 0.7874 -0.4064)
			(end 0.7874 0.4064)
			(stroke
				(width 0.1524)
				(type default)
			)
			(layer "F.SilkS")
		)
		(fp_line
			(start -0.7874 -0.4064)
			(end 0.7874 -0.4064)
			(stroke
				(width 0.1524)
				(type default)
			)
			(layer "F.SilkS")
		)
		(fp_line
			(start 0.7874 0.4064)
			(end -0.7874 0.4064)
			(stroke
				(width 0.1524)
				(type default)
			)
			(layer "F.SilkS")
		)
		(fp_line
			(start -0.7874 0.4064)
			(end -0.7874 -0.4064)
			(stroke
				(width 0.1524)
				(type default)
			)
			(layer "F.SilkS")
		)
		(fp_line
			(start -0.12065 -0.305054)
			(end -0.12065 -0.2794)
			(stroke
				(width 0.1)
				(type default)
			)
			(layer "F.Fab")
		)
		(fp_line
			(start -0.67945 -0.305054)
			(end -0.12065 -0.305054)
			(stroke
				(width 0.1)
				(type default)
			)
			(layer "F.Fab")
		)
		(fp_line
			(start 0.67945 -0.3048)
			(end 0.67945 0.3048)
			(stroke
				(width 0.1)
				(type default)
			)
			(layer "F.Fab")
		)
		(fp_line
			(start 0.12065 -0.3048)
			(end 0.67945 -0.3048)
			(stroke
				(width 0.1)
				(type default)
			)
			(layer "F.Fab")
		)
		(fp_line
			(start 0.12065 -0.2794)
			(end 0.12065 -0.3048)
			(stroke
				(width 0.1)
				(type default)
			)
			(layer "F.Fab")
		)
		(fp_line
			(start -0.12065 -0.2794)
			(end 0.12065 -0.2794)
			(stroke
				(width 0.1)
				(type default)
			)
			(layer "F.Fab")
		)
		(fp_line
			(start 0.120396 0.2794)
			(end -0.12065 0.2794)
			(stroke
				(width 0.1)
				(type default)
			)
			(layer "F.Fab")
		)
		(fp_line
			(start -0.12065 0.2794)
			(end -0.12065 0.3048)
			(stroke
				(width 0.1)
				(type default)
			)
			(layer "F.Fab")
		)
		(fp_line
			(start 0.67945 0.3048)
			(end 0.120396 0.3048)
			(stroke
				(width 0.1)
				(type default)
			)
			(layer "F.Fab")
		)
		(fp_line
			(start 0.120396 0.3048)
			(end 0.120396 0.2794)
			(stroke
				(width 0.1)
				(type default)
			)
			(layer "F.Fab")
		)
		(fp_line
			(start -0.12065 0.3048)
			(end -0.67945 0.3048)
			(stroke
				(width 0.1)
				(type default)
			)
			(layer "F.Fab")
		)
		(fp_line
			(start -0.67945 0.3048)
			(end -0.67945 -0.305054)
			(stroke
				(width 0.1)
				(type default)
			)
			(layer "F.Fab")
		)
		(pad "1" smd circle
			(at -0.40005 0 90)
			(size 0 0)
			(layers "F.Cu" "F.Mask" "F.Paste")
			(net "P3V3_OCP_GATE_PU207_2")
		)
		(pad "2" smd circle
			(at 0.40005 0 90)
			(size 0 0)
			(layers "F.Cu" "F.Mask" "F.Paste")
			(net "GND")
		)
	)
	(footprint ""
		(layer "F.Cu")
		(at 20.11426 -165.751256)
		(property "Reference" "R1718"
			(at 0 0 0)
			(layer "F.SilkS")
			(hide yes)
			(effects
				(font
					(size 1.27 1.27)
				)
			)
		)
		(property "Value" ""
			(at 0 0 0)
			(layer "F.Fab")
			(effects
				(font
					(size 1.27 1.27)
				)
			)
		)
		(duplicate_pad_numbers_are_jumpers no)
		(fp_line
			(start -0.7874 -0.4064)
			(end 0.7874 -0.4064)
			(stroke
				(width 0.1524)
				(type default)
			)
			(layer "F.SilkS")
		)
		(fp_line
			(start -0.7874 0.4064)
			(end -0.7874 -0.4064)
			(stroke
				(width 0.1524)
				(type default)
			)
			(layer "F.SilkS")
		)
		(fp_line
			(start 0.7874 -0.4064)
			(end 0.7874 0.4064)
			(stroke
				(width 0.1524)
				(type default)
			)
			(layer "F.SilkS")
		)
		(fp_line
			(start 0.7874 0.4064)
			(end -0.7874 0.4064)
			(stroke
				(width 0.1524)
				(type default)
			)
			(layer "F.SilkS")
		)
		(fp_line
			(start -0.67945 -0.305054)
			(end -0.12065 -0.305054)
			(stroke
				(width 0.1)
				(type default)
			)
			(layer "F.Fab")
		)
		(fp_line
			(start -0.67945 0.3048)
			(end -0.67945 -0.305054)
			(stroke
				(width 0.1)
				(type default)
			)
			(layer "F.Fab")
		)
		(fp_line
			(start -0.12065 -0.305054)
			(end -0.12065 -0.2794)
			(stroke
				(width 0.1)
				(type default)
			)
			(layer "F.Fab")
		)
		(fp_line
			(start -0.12065 -0.2794)
			(end 0.12065 -0.2794)
			(stroke
				(width 0.1)
				(type default)
			)
			(layer "F.Fab")
		)
		(fp_line
			(start -0.12065 0.2794)
			(end -0.12065 0.3048)
			(stroke
				(width 0.1)
				(type default)
			)
			(layer "F.Fab")
		)
		(fp_line
			(start -0.12065 0.3048)
			(end -0.67945 0.3048)
			(stroke
				(width 0.1)
				(type default)
			)
			(layer "F.Fab")
		)
		(fp_line
			(start 0.120396 0.2794)
			(end -0.12065 0.2794)
			(stroke
				(width 0.1)
				(type default)
			)
			(layer "F.Fab")
		)
		(fp_line
			(start 0.120396 0.3048)
			(end 0.120396 0.2794)
			(stroke
				(width 0.1)
				(type default)
			)
			(layer "F.Fab")
		)
		(fp_line
			(start 0.12065 -0.3048)
			(end 0.67945 -0.3048)
			(stroke
				(width 0.1)
				(type default)
			)
			(layer "F.Fab")
		)
		(fp_line
			(start 0.12065 -0.2794)
			(end 0.12065 -0.3048)
			(stroke
				(width 0.1)
				(type default)
			)
			(layer "F.Fab")
		)
		(fp_line
			(start 0.67945 -0.3048)
			(end 0.67945 0.3048)
			(stroke
				(width 0.1)
				(type default)
			)
			(layer "F.Fab")
		)
		(fp_line
			(start 0.67945 0.3048)
			(end 0.120396 0.3048)
			(stroke
				(width 0.1)
				(type default)
			)
			(layer "F.Fab")
		)
		(pad "1" smd circle
			(at -0.40005 0)
			(size 0 0)
			(layers "F.Cu" "F.Mask" "F.Paste")
			(net "PVNN_TERM_CPU1")
		)
		(pad "2" smd circle
			(at 0.40005 0)
			(size 0 0)
			(layers "F.Cu" "F.Mask" "F.Paste")
			(net "SVID_CLK1_CPU1_R")
		)
	)
)
